(kicad_pcb
	(version 20241229)
	(generator "pcbnew")
	(generator_version "9.0")
	(general
		(thickness 1.62)
		(legacy_teardrops no)
	)
	(paper "A3")
	(title_block
		(title "COM Express 7 Baseboard")
		(date "2025-02-04")
		(rev "1.1.2")
		(company "Antmicro Ltd")
		(comment 1 "www.antmicro.com")
		(comment 9 "footprints 697-701 of 802")
	)
	(layers
		(0 "F.Cu" signal)
		(4 "In1.Cu" signal)
		(6 "In2.Cu" signal)
		(8 "In3.Cu" signal)
		(10 "In4.Cu" signal)
		(12 "In5.Cu" signal)
		(14 "In6.Cu" signal)
		(2 "B.Cu" signal)
		(9 "F.Adhes" user "F.Adhesive")
		(11 "B.Adhes" user "B.Adhesive")
		(13 "F.Paste" user)
		(15 "B.Paste" user)
		(5 "F.SilkS" user "F.Silkscreen")
		(7 "B.SilkS" user "B.Silkscreen")
		(1 "F.Mask" user)
		(3 "B.Mask" user)
		(17 "Dwgs.User" user "User.Drawings")
		(19 "Cmts.User" user "User.Comments")
		(21 "Eco1.User" user "User.Eco1")
		(23 "Eco2.User" user "User.Eco2")
		(25 "Edge.Cuts" user)
		(27 "Margin" user)
		(31 "F.CrtYd" user "F.Courtyard")
		(29 "B.CrtYd" user "B.Courtyard")
		(35 "F.Fab" user)
		(33 "B.Fab" user)
	)
	(footprint "antmicro-footprints:C_0402_1005Metric"
		(layer "B.Cu")
		(at 150.45 138.36 -90)
		(descr "Capacitor SMD 0402")
		(tags "capacitor SMD 0402")
		(property "Reference" "C172"
			(at -0.3 0.55 90)
			(layer "B.SilkS")
			(effects
				(font
					(size 0.7 0.7)
					(thickness 0.15)
				)
				(justify left bottom mirror)
			)
		)
		(property "Value" "C_100n_0402"
			(at -1.022927 -2.155213 90)
			(layer "B.Fab")
			(effects
				(font
					(size 0.7 0.7)
					(thickness 0.15)
				)
				(justify left bottom mirror)
			)
		)
		(property "Datasheet" "https://www.murata.com/products/productdetail?partno=GRM155R61H104KE14%23"
			(at 0 0 270)
			(layer "F.Fab")
			(hide yes)
			(effects
				(font
					(size 1.27 1.27)
					(thickness 0.15)
				)
			)
		)
		(property "Author" "Antmicro"
			(at 12.09 288.81 0)
			(layer "B.Fab")
			(hide yes)
			(effects
				(font
					(size 1 1)
					(thickness 0.15)
				)
				(justify mirror)
			)
		)
		(property "Dielectric" "X5R"
			(at 12.09 288.81 0)
			(layer "B.Fab")
			(hide yes)
			(effects
				(font
					(size 1 1)
					(thickness 0.15)
				)
				(justify mirror)
			)
		)
		(property "License" "Apache-2.0"
			(at 12.09 288.81 0)
			(layer "B.Fab")
			(hide yes)
			(effects
				(font
					(size 1 1)
					(thickness 0.15)
				)
				(justify mirror)
			)
		)
		(property "MPN" "GRM155R61H104KE14D"
			(at 12.09 288.81 0)
			(layer "B.Fab")
			(hide yes)
			(effects
				(font
					(size 1 1)
					(thickness 0.15)
				)
				(justify mirror)
			)
		)
		(property "Manufacturer" "Murata"
			(at 12.09 288.81 0)
			(layer "B.Fab")
			(hide yes)
			(effects
				(font
					(size 1 1)
					(thickness 0.15)
				)
				(justify mirror)
			)
		)
		(property "Public" "False"
			(at 12.09 288.81 0)
			(layer "B.Fab")
			(hide yes)
			(effects
				(font
					(size 1 1)
					(thickness 0.15)
				)
				(justify mirror)
			)
		)
		(property "Val" "100n"
			(at 12.09 288.81 0)
			(layer "B.Fab")
			(hide yes)
			(effects
				(font
					(size 1 1)
					(thickness 0.15)
				)
				(justify mirror)
			)
		)
		(property "Voltage" "50V"
			(at 12.09 288.81 0)
			(layer "B.Fab")
			(hide yes)
			(effects
				(font
					(size 1 1)
					(thickness 0.15)
				)
				(justify mirror)
			)
		)
		(sheetname "KR to SFI #1")
		(sheetfile "kr_sfi.kicad_sch")
		(attr smd)
		(fp_rect
			(start -0.925 0.47)
			(end 0.925 -0.47)
			(stroke
				(width 0.05)
				(type default)
			)
			(fill no)
			(layer "B.CrtYd")
		)
		(fp_line
			(start -0.494 0.25)
			(end -0.494 -0.248)
			(stroke
				(width 0.15)
				(type solid)
			)
			(layer "B.Fab")
		)
		(fp_line
			(start 0.504 0.25)
			(end -0.494 0.25)
			(stroke
				(width 0.15)
				(type solid)
			)
			(layer "B.Fab")
		)
		(fp_line
			(start -0.494 -0.248)
			(end 0.504 -0.248)
			(stroke
				(width 0.15)
				(type solid)
			)
			(layer "B.Fab")
		)
		(fp_line
			(start 0.504 -0.248)
			(end 0.504 0.25)
			(stroke
				(width 0.15)
				(type solid)
			)
			(layer "B.Fab")
		)
		(pad "1" smd roundrect
			(at -0.48 0 270)
			(size 0.59 0.64)
			(layers "B.Cu" "B.Mask" "B.Paste")
			(roundrect_rratio 0.25)
			(net 1 "GND")
			(pintype "passive")
			(teardrops
				(best_length_ratio 0.2)
				(max_length 1)
				(best_width_ratio 0.9)
				(max_width 2)
				(curved_edges yes)
				(filter_ratio 0.9)
				(enabled yes)
				(allow_two_segments yes)
				(prefer_zone_connections yes)
			)
		)
		(pad "2" smd roundrect
			(at 0.48 0 270)
			(size 0.59 0.64)
			(layers "B.Cu" "B.Mask" "B.Paste")
			(roundrect_rratio 0.25)
			(net 74 "+1V0")
			(pintype "passive")
			(teardrops
				(best_length_ratio 0.2)
				(max_length 1)
				(best_width_ratio 0.9)
				(max_width 2)
				(curved_edges yes)
				(filter_ratio 0.9)
				(enabled yes)
				(allow_two_segments yes)
				(prefer_zone_connections yes)
			)
		)
	)
	(footprint "antmicro-footprints:TP_SMD_0.75mm"
		(layer "B.Cu")
		(at 193.05 163.35 90)
		(property "Reference" "TP33"
			(at 0.85 0.45 270)
			(layer "B.SilkS")
			(effects
				(font
					(size 0.7 0.7)
					(thickness 0.15)
				)
				(justify right bottom mirror)
			)
		)
		(property "Value" "TP_0.75mm_SMD"
			(at 0 -1.2 90)
			(layer "B.Fab")
			(effects
				(font
					(size 0.7 0.7)
					(thickness 0.15)
				)
				(justify right bottom mirror)
			)
		)
		(property "Author" "Antmicro"
			(at 362.31 -49.29 0)
			(layer "B.Fab")
			(hide yes)
			(effects
				(font
					(size 1 1)
					(thickness 0.15)
				)
				(justify mirror)
			)
		)
		(property "License" "Apache-2.0"
			(at 362.31 -49.29 0)
			(layer "B.Fab")
			(hide yes)
			(effects
				(font
					(size 1 1)
					(thickness 0.15)
				)
				(justify mirror)
			)
		)
		(property "MPN" ""
			(at 362.31 -49.29 0)
			(layer "B.Fab")
			(hide yes)
			(effects
				(font
					(size 1 1)
					(thickness 0.15)
				)
				(justify mirror)
			)
		)
		(property "Manufacturer" ""
			(at 362.31 -49.29 0)
			(layer "B.Fab")
			(hide yes)
			(effects
				(font
					(size 1 1)
					(thickness 0.15)
				)
				(justify mirror)
			)
		)
		(property "Public" "False"
			(at 362.31 -49.29 0)
			(layer "B.Fab")
			(hide yes)
			(effects
				(font
					(size 1 1)
					(thickness 0.15)
				)
				(justify mirror)
			)
		)
		(sheetname "Com Express 7 MGMT")
		(sheetfile "com_express_7_mgmt.kicad_sch")
		(attr exclude_from_pos_files exclude_from_bom)
		(fp_circle
			(center 0 0)
			(end 0.475 0)
			(stroke
				(width 0.05)
				(type default)
			)
			(fill no)
			(layer "B.CrtYd")
		)
		(pad "1" smd circle
			(at 0 0 90)
			(size 0.75 0.75)
			(layers "B.Cu" "B.Mask")
			(net 381 "Net-(J12D-~{SYS_RESET})")
			(pinfunction "1")
			(pintype "passive")
			(teardrops
				(best_length_ratio 0.4)
				(max_length 1)
				(best_width_ratio 0.9)
				(max_width 2)
				(curved_edges yes)
				(filter_ratio 0.9)
				(enabled yes)
				(allow_two_segments yes)
				(prefer_zone_connections yes)
			)
		)
	)
	(footprint "antmicro-footprints:C_0402_1005Metric"
		(layer "B.Cu")
		(at 154.45 137.36 -90)
		(descr "Capacitor SMD 0402")
		(tags "capacitor SMD 0402")
		(property "Reference" "C164"
			(at -1.4 -1.4 90)
			(layer "B.SilkS")
			(effects
				(font
					(size 0.7 0.7)
					(thickness 0.15)
				)
				(justify left bottom mirror)
			)
		)
		(property "Value" "C_100n_0402"
			(at -1.022927 -2.155213 90)
			(layer "B.Fab")
			(effects
				(font
					(size 0.7 0.7)
					(thickness 0.15)
				)
				(justify left bottom mirror)
			)
		)
		(property "Datasheet" "https://www.murata.com/products/productdetail?partno=GRM155R61H104KE14%23"
			(at 0 0 270)
			(layer "F.Fab")
			(hide yes)
			(effects
				(font
					(size 1.27 1.27)
					(thickness 0.15)
				)
			)
		)
		(property "Author" "Antmicro"
			(at 17.09 291.81 0)
			(layer "B.Fab")
			(hide yes)
			(effects
				(font
					(size 1 1)
					(thickness 0.15)
				)
				(justify mirror)
			)
		)
		(property "Dielectric" "X5R"
			(at 17.09 291.81 0)
			(layer "B.Fab")
			(hide yes)
			(effects
				(font
					(size 1 1)
					(thickness 0.15)
				)
				(justify mirror)
			)
		)
		(property "License" "Apache-2.0"
			(at 17.09 291.81 0)
			(layer "B.Fab")
			(hide yes)
			(effects
				(font
					(size 1 1)
					(thickness 0.15)
				)
				(justify mirror)
			)
		)
		(property "MPN" "GRM155R61H104KE14D"
			(at 17.09 291.81 0)
			(layer "B.Fab")
			(hide yes)
			(effects
				(font
					(size 1 1)
					(thickness 0.15)
				)
				(justify mirror)
			)
		)
		(property "Manufacturer" "Murata"
			(at 17.09 291.81 0)
			(layer "B.Fab")
			(hide yes)
			(effects
				(font
					(size 1 1)
					(thickness 0.15)
				)
				(justify mirror)
			)
		)
		(property "Public" "False"
			(at 17.09 291.81 0)
			(layer "B.Fab")
			(hide yes)
			(effects
				(font
					(size 1 1)
					(thickness 0.15)
				)
				(justify mirror)
			)
		)
		(property "Val" "100n"
			(at 17.09 291.81 0)
			(layer "B.Fab")
			(hide yes)
			(effects
				(font
					(size 1 1)
					(thickness 0.15)
				)
				(justify mirror)
			)
		)
		(property "Voltage" "50V"
			(at 17.09 291.81 0)
			(layer "B.Fab")
			(hide yes)
			(effects
				(font
					(size 1 1)
					(thickness 0.15)
				)
				(justify mirror)
			)
		)
		(sheetname "KR to SFI #1")
		(sheetfile "kr_sfi.kicad_sch")
		(attr smd)
		(fp_rect
			(start -0.925 0.47)
			(end 0.925 -0.47)
			(stroke
				(width 0.05)
				(type default)
			)
			(fill no)
			(layer "B.CrtYd")
		)
		(fp_line
			(start -0.494 0.25)
			(end -0.494 -0.248)
			(stroke
				(width 0.15)
				(type solid)
			)
			(layer "B.Fab")
		)
		(fp_line
			(start 0.504 0.25)
			(end -0.494 0.25)
			(stroke
				(width 0.15)
				(type solid)
			)
			(layer "B.Fab")
		)
		(fp_line
			(start -0.494 -0.248)
			(end 0.504 -0.248)
			(stroke
				(width 0.15)
				(type solid)
			)
			(layer "B.Fab")
		)
		(fp_line
			(start 0.504 -0.248)
			(end 0.504 0.25)
			(stroke
				(width 0.15)
				(type solid)
			)
			(layer "B.Fab")
		)
		(pad "1" smd roundrect
			(at -0.48 0 270)
			(size 0.59 0.64)
			(layers "B.Cu" "B.Mask" "B.Paste")
			(roundrect_rratio 0.25)
			(net 1 "GND")
			(pintype "passive")
			(teardrops
				(best_length_ratio 0.2)
				(max_length 1)
				(best_width_ratio 0.9)
				(max_width 2)
				(curved_edges yes)
				(filter_ratio 0.9)
				(enabled yes)
				(allow_two_segments yes)
				(prefer_zone_connections yes)
			)
		)
		(pad "2" smd roundrect
			(at 0.48 0 270)
			(size 0.59 0.64)
			(layers "B.Cu" "B.Mask" "B.Paste")
			(roundrect_rratio 0.25)
			(net 74 "+1V0")
			(pintype "passive")
			(teardrops
				(best_length_ratio 0.2)
				(max_length 1)
				(best_width_ratio 0.9)
				(max_width 2)
				(curved_edges yes)
				(filter_ratio 0.9)
				(enabled yes)
				(allow_two_segments yes)
				(prefer_zone_connections yes)
			)
		)
	)
	(footprint "antmicro-footprints:C_0402_1005Metric"
		(layer "B.Cu")
		(at 118.48 168.91)
		(descr "Capacitor SMD 0402")
		(tags "capacitor SMD 0402")
		(property "Reference" "C28"
			(at -1.03 -0.5 0)
			(layer "B.SilkS")
			(effects
				(font
					(size 0.7 0.7)
					(thickness 0.15)
				)
				(justify right bottom mirror)
			)
		)
		(property "Value" "C_100n_0402"
			(at -1.022927 -2.155213 0)
			(layer "B.Fab")
			(effects
				(font
					(size 0.7 0.7)
					(thickness 0.15)
				)
				(justify right bottom mirror)
			)
		)
		(property "Datasheet" "https://www.murata.com/products/productdetail?partno=GRM155R61H104KE14%23"
			(at 0 0 0)
			(layer "F.Fab")
			(hide yes)
			(effects
				(font
					(size 1.27 1.27)
					(thickness 0.15)
				)
			)
		)
		(property "Author" "Antmicro"
			(at 0 0 0)
			(layer "B.Fab")
			(hide yes)
			(effects
				(font
					(size 1 1)
					(thickness 0.15)
				)
				(justify mirror)
			)
		)
		(property "Dielectric" "X5R"
			(at 0 0 0)
			(layer "B.Fab")
			(hide yes)
			(effects
				(font
					(size 1 1)
					(thickness 0.15)
				)
				(justify mirror)
			)
		)
		(property "License" "Apache-2.0"
			(at 0 0 0)
			(layer "B.Fab")
			(hide yes)
			(effects
				(font
					(size 1 1)
					(thickness 0.15)
				)
				(justify mirror)
			)
		)
		(property "MPN" "GRM155R61H104KE14D"
			(at 0 0 0)
			(layer "B.Fab")
			(hide yes)
			(effects
				(font
					(size 1 1)
					(thickness 0.15)
				)
				(justify mirror)
			)
		)
		(property "Manufacturer" "Murata"
			(at 0 0 0)
			(layer "B.Fab")
			(hide yes)
			(effects
				(font
					(size 1 1)
					(thickness 0.15)
				)
				(justify mirror)
			)
		)
		(property "Public" "False"
			(at 0 0 0)
			(layer "B.Fab")
			(hide yes)
			(effects
				(font
					(size 1 1)
					(thickness 0.15)
				)
				(justify mirror)
			)
		)
		(property "Val" "100n"
			(at 0 0 0)
			(layer "B.Fab")
			(hide yes)
			(effects
				(font
					(size 1 1)
					(thickness 0.15)
				)
				(justify mirror)
			)
		)
		(property "Voltage" "50V"
			(at 0 0 0)
			(layer "B.Fab")
			(hide yes)
			(effects
				(font
					(size 1 1)
					(thickness 0.15)
				)
				(justify mirror)
			)
		)
		(sheetname "2xSFP+")
		(sheetfile "2xSFP+.kicad_sch")
		(attr smd)
		(fp_rect
			(start -0.925 0.47)
			(end 0.925 -0.47)
			(stroke
				(width 0.05)
				(type default)
			)
			(fill no)
			(layer "B.CrtYd")
		)
		(fp_line
			(start -0.494 -0.248)
			(end 0.504 -0.248)
			(stroke
				(width 0.15)
				(type solid)
			)
			(layer "B.Fab")
		)
		(fp_line
			(start -0.494 0.25)
			(end -0.494 -0.248)
			(stroke
				(width 0.15)
				(type solid)
			)
			(layer "B.Fab")
		)
		(fp_line
			(start 0.504 -0.248)
			(end 0.504 0.25)
			(stroke
				(width 0.15)
				(type solid)
			)
			(layer "B.Fab")
		)
		(fp_line
			(start 0.504 0.25)
			(end -0.494 0.25)
			(stroke
				(width 0.15)
				(type solid)
			)
			(layer "B.Fab")
		)
		(pad "1" smd roundrect
			(at -0.48 0)
			(size 0.59 0.64)
			(layers "B.Cu" "B.Mask" "B.Paste")
			(roundrect_rratio 0.25)
			(net 53 "/2xSFP+/SH")
			(pintype "passive")
			(teardrops
				(best_length_ratio 0.2)
				(max_length 1)
				(best_width_ratio 0.9)
				(max_width 2)
				(curved_edges yes)
				(filter_ratio 0.9)
				(enabled yes)
				(allow_two_segments yes)
				(prefer_zone_connections yes)
			)
		)
		(pad "2" smd roundrect
			(at 0.48 0)
			(size 0.59 0.64)
			(layers "B.Cu" "B.Mask" "B.Paste")
			(roundrect_rratio 0.25)
			(net 1 "GND")
			(pintype "passive")
			(teardrops
				(best_length_ratio 0.2)
				(max_length 1)
				(best_width_ratio 0.9)
				(max_width 2)
				(curved_edges yes)
				(filter_ratio 0.9)
				(enabled yes)
				(allow_two_segments yes)
				(prefer_zone_connections yes)
			)
		)
	)
	(footprint "antmicro-footprints:C_0603_1608Metric"
		(layer "B.Cu")
		(at 147.3 132.078 -90)
		(descr "Capacitor SMD 0603")
		(tags "capacitor 0603")
		(property "Reference" "C156"
			(at -6.968 1.9 90)
			(layer "B.SilkS")
			(effects
				(font
					(size 0.7 0.7)
					(thickness 0.15)
				)
				(justify left bottom mirror)
			)
		)
		(property "Value" "C_22u_16V_0603"
			(at -1.42757 -1.770288 90)
			(layer "B.Fab")
			(effects
				(font
					(size 0.7 0.7)
					(thickness 0.15)
				)
				(justify left bottom mirror)
			)
		)
		(property "Datasheet" "https://product.samsungsem.com/mlcc/CL10A226MO7JZN.do"
			(at 0 0 270)
			(layer "F.Fab")
			(hide yes)
			(effects
				(font
					(size 1.27 1.27)
					(thickness 0.15)
				)
			)
		)
		(property "Author" "Antmicro"
			(at 15.222 279.378 0)
			(layer "B.Fab")
			(hide yes)
			(effects
				(font
					(size 1 1)
					(thickness 0.15)
				)
				(justify mirror)
			)
		)
		(property "Dielectric" ""
			(at 15.222 279.378 0)
			(layer "B.Fab")
			(hide yes)
			(effects
				(font
					(size 1 1)
					(thickness 0.15)
				)
				(justify mirror)
			)
		)
		(property "License" "Apache-2.0"
			(at 15.222 279.378 0)
			(layer "B.Fab")
			(hide yes)
			(effects
				(font
					(size 1 1)
					(thickness 0.15)
				)
				(justify mirror)
			)
		)
		(property "MPN" "CL10A226MO7JZNC"
			(at 15.222 279.378 0)
			(layer "B.Fab")
			(hide yes)
			(effects
				(font
					(size 1 1)
					(thickness 0.15)
				)
				(justify mirror)
			)
		)
		(property "Manufacturer" "Samsung Electro-Mechanics"
			(at 15.222 279.378 0)
			(layer "B.Fab")
			(hide yes)
			(effects
				(font
					(size 1 1)
					(thickness 0.15)
				)
				(justify mirror)
			)
		)
		(property "Public" "False"
			(at 15.222 279.378 0)
			(layer "B.Fab")
			(hide yes)
			(effects
				(font
					(size 1 1)
					(thickness 0.15)
				)
				(justify mirror)
			)
		)
		(property "Val" "22u"
			(at 15.222 279.378 0)
			(layer "B.Fab")
			(hide yes)
			(effects
				(font
					(size 1 1)
					(thickness 0.15)
				)
				(justify mirror)
			)
		)
		(property "Voltage" "16V"
			(at 15.222 279.378 0)
			(layer "B.Fab")
			(hide yes)
			(effects
				(font
					(size 1 1)
					(thickness 0.15)
				)
				(justify mirror)
			)
		)
		(sheetname "KR to SFI #1")
		(sheetfile "kr_sfi.kicad_sch")
		(attr smd)
		(fp_line
			(start 0.15 0.4)
			(end -0.15 0.4)
			(stroke
				(width 0.15)
				(type solid)
			)
			(layer "B.SilkS")
		)
		(fp_line
			(start 0.15 -0.4)
			(end -0.15 -0.4)
			(stroke
				(width 0.15)
				(type solid)
			)
			(layer "B.SilkS")
		)
		(fp_rect
			(start -1.25 0.65)
			(end 1.25 -0.65)
			(stroke
				(width 0.05)
				(type solid)
			)
			(fill no)
			(layer "B.CrtYd")
		)
		(fp_rect
			(start -0.8 0.4)
			(end 0.8 -0.4)
			(stroke
				(width 0.15)
				(type solid)
			)
			(fill no)
			(layer "B.Fab")
		)
		(pad "1" smd roundrect
			(at -0.7 0 270)
			(size 0.8 1)
			(layers "B.Cu" "B.Mask" "B.Paste")
			(roundrect_rratio 0.2)
			(net 1 "GND")
			(pintype "passive")
			(teardrops
				(best_length_ratio 0.2)
				(max_length 1)
				(best_width_ratio 0.9)
				(max_width 2)
				(curved_edges yes)
				(filter_ratio 0.9)
				(enabled yes)
				(allow_two_segments yes)
				(prefer_zone_connections yes)
			)
		)
		(pad "2" smd roundrect
			(at 0.7 0 270)
			(size 0.8 1)
			(layers "B.Cu" "B.Mask" "B.Paste")
			(roundrect_rratio 0.2)
			(net 78 "+1V8")
			(pintype "passive")
			(teardrops
				(best_length_ratio 0.2)
				(max_length 1)
				(best_width_ratio 0.9)
				(max_width 2)
				(curved_edges yes)
				(filter_ratio 0.9)
				(enabled yes)
				(allow_two_segments yes)
				(prefer_zone_connections yes)
			)
		)
	)
)
